(kicad_pcb
	(version 20241229)
	(generator "pcbnew")
	(generator_version "9.0")
	(general
		(thickness 1.63)
		(legacy_teardrops no)
	)
	(paper "A4")
	(title_block
		(title "CM4 Baseboard")
		(date "2026-01-05")
		(rev "1.1.1")
		(company "Antmicro Ltd")
		(comment 1 "www.antmicro.com")
		(comment 9 "footprints 186-191 of 506")
	)
	(layers
		(0 "F.Cu" signal)
		(4 "In1.Cu" power)
		(6 "In2.Cu" power)
		(8 "In3.Cu" signal)
		(10 "In4.Cu" signal)
		(2 "B.Cu" signal)
		(9 "F.Adhes" user "F.Adhesive")
		(11 "B.Adhes" user "B.Adhesive")
		(13 "F.Paste" user)
		(15 "B.Paste" user)
		(5 "F.SilkS" user "F.Silkscreen")
		(7 "B.SilkS" user "B.Silkscreen")
		(1 "F.Mask" user)
		(3 "B.Mask" user)
		(17 "Dwgs.User" user "User.Drawings")
		(19 "Cmts.User" user "User.Comments")
		(21 "Eco1.User" user "User.Eco1")
		(23 "Eco2.User" user "User.Eco2")
		(25 "Edge.Cuts" user)
		(27 "Margin" user)
		(31 "F.CrtYd" user "F.Courtyard")
		(29 "B.CrtYd" user "B.Courtyard")
		(35 "F.Fab" user)
		(33 "B.Fab" user)
	)
	(footprint "antmicro-footprints:TP_SMD_0.75mm"
		(layer "F.Cu")
		(at 80.3 137.65)
		(property "Reference" "TP916"
			(at -1.75 3.95 90)
			(layer "F.SilkS")
			(effects
				(font
					(size 0.7 0.7)
					(thickness 0.15)
				)
				(justify left bottom)
			)
		)
		(property "Value" "TP_0.75mm_SMD"
			(at 0 1.2 0)
			(layer "F.Fab")
			(effects
				(font
					(size 0.7 0.7)
					(thickness 0.15)
				)
				(justify left bottom)
			)
		)
		(property "MPN" ""
			(at 0 0 0)
			(unlocked yes)
			(layer "F.Fab")
			(hide yes)
			(effects
				(font
					(size 1 1)
					(thickness 0.15)
				)
			)
		)
		(property "Manufacturer" ""
			(at 0 0 0)
			(unlocked yes)
			(layer "F.Fab")
			(hide yes)
			(effects
				(font
					(size 1 1)
					(thickness 0.15)
				)
			)
		)
		(property "Author" "Antmicro"
			(at 0 0 0)
			(unlocked yes)
			(layer "F.Fab")
			(hide yes)
			(effects
				(font
					(size 1 1)
					(thickness 0.15)
				)
			)
		)
		(property "License" "Apache-2.0"
			(at 0 0 0)
			(unlocked yes)
			(layer "F.Fab")
			(hide yes)
			(effects
				(font
					(size 1 1)
					(thickness 0.15)
				)
			)
		)
		(sheetname "/USB/")
		(sheetfile "usb.kicad_sch")
		(attr exclude_from_pos_files exclude_from_bom)
		(fp_circle
			(center 0 0)
			(end 0.475 0)
			(stroke
				(width 0.05)
				(type default)
			)
			(fill no)
			(layer "F.CrtYd")
		)
		(fp_text user "License: Apache-2.0"
			(at -0.4 5.101 0)
			(layer "F.Fab")
			(effects
				(font
					(size 0.7 0.7)
					(thickness 0.15)
				)
				(justify left bottom)
			)
		)
		(fp_text user "${REFERENCE}"
			(at -0.4 2.7 0)
			(layer "F.Fab")
			(effects
				(font
					(size 0.7 0.7)
					(thickness 0.15)
				)
				(justify left bottom)
			)
		)
		(fp_text user "Author: Antmicro"
			(at -0.4 3.901 0)
			(layer "F.Fab")
			(effects
				(font
					(size 0.7 0.7)
					(thickness 0.15)
				)
				(justify left bottom)
			)
		)
		(pad "1" smd circle
			(at 0 0)
			(size 0.75 0.75)
			(layers "F.Cu" "F.Mask")
			(net 441 "Net-(U905-GPIO4)")
			(pinfunction "1")
			(pintype "passive")
		)
	)
	(footprint "antmicro-footprints:C_0402_1005Metric"
		(layer "F.Cu")
		(at 76.617962 176.6165 90)
		(descr "Capacitor SMD 0402")
		(tags "capacitor SMD 0402")
		(property "Reference" "C815"
			(at 0.9755 -1.98 180)
			(layer "F.SilkS")
			(effects
				(font
					(size 0.7 0.7)
					(thickness 0.15)
				)
				(justify left bottom)
			)
		)
		(property "Value" "C_10p_0402"
			(at -1.022927 2.155213 90)
			(layer "F.Fab")
			(effects
				(font
					(size 0.7 0.7)
					(thickness 0.15)
				)
				(justify left bottom)
			)
		)
		(property "Datasheet" "https://www.murata.com/products/productdetail?partno=GCM1555C1H100GA16%23"
			(at 0 0 90)
			(layer "F.Fab")
			(hide yes)
			(effects
				(font
					(size 1.27 1.27)
					(thickness 0.15)
				)
			)
		)
		(property "MPN" "GCM1555C1H100GA16D"
			(at 0 0 90)
			(unlocked yes)
			(layer "F.Fab")
			(hide yes)
			(effects
				(font
					(size 1 1)
					(thickness 0.15)
				)
			)
		)
		(property "Manufacturer" "Murata"
			(at 0 0 90)
			(unlocked yes)
			(layer "F.Fab")
			(hide yes)
			(effects
				(font
					(size 1 1)
					(thickness 0.15)
				)
			)
		)
		(property "License" "Apache-2.0"
			(at 0 0 90)
			(unlocked yes)
			(layer "F.Fab")
			(hide yes)
			(effects
				(font
					(size 1 1)
					(thickness 0.15)
				)
			)
		)
		(property "Author" "Antmicro"
			(at 0 0 90)
			(unlocked yes)
			(layer "F.Fab")
			(hide yes)
			(effects
				(font
					(size 1 1)
					(thickness 0.15)
				)
			)
		)
		(property "Val" "10p"
			(at 0 0 90)
			(unlocked yes)
			(layer "F.Fab")
			(hide yes)
			(effects
				(font
					(size 1 1)
					(thickness 0.15)
				)
			)
		)
		(property "Voltage" "50V"
			(at 0 0 90)
			(unlocked yes)
			(layer "F.Fab")
			(hide yes)
			(effects
				(font
					(size 1 1)
					(thickness 0.15)
				)
			)
		)
		(property "Dielectric" "C0G"
			(at 0 0 90)
			(unlocked yes)
			(layer "F.Fab")
			(hide yes)
			(effects
				(font
					(size 1 1)
					(thickness 0.15)
				)
			)
		)
		(sheetname "/Peripherals/")
		(sheetfile "peripherals.kicad_sch")
		(attr smd)
		(fp_rect
			(start -0.925 -0.47)
			(end 0.925 0.47)
			(stroke
				(width 0.05)
				(type default)
			)
			(fill no)
			(layer "F.CrtYd")
		)
		(fp_line
			(start 0.504 -0.25)
			(end 0.504 0.248)
			(stroke
				(width 0.15)
				(type solid)
			)
			(layer "F.Fab")
		)
		(fp_line
			(start -0.494 -0.25)
			(end 0.504 -0.25)
			(stroke
				(width 0.15)
				(type solid)
			)
			(layer "F.Fab")
		)
		(fp_line
			(start 0.504 0.248)
			(end -0.494 0.248)
			(stroke
				(width 0.15)
				(type solid)
			)
			(layer "F.Fab")
		)
		(fp_line
			(start -0.494 0.248)
			(end -0.494 -0.25)
			(stroke
				(width 0.15)
				(type solid)
			)
			(layer "F.Fab")
		)
		(fp_text user "${REFERENCE}"
			(at -0.939 4.599 90)
			(layer "F.Fab")
			(effects
				(font
					(size 0.7 0.7)
					(thickness 0.15)
				)
				(justify left bottom)
			)
		)
		(fp_text user "License: Apache-2.0"
			(at -0.939 5.799 90)
			(layer "F.Fab")
			(effects
				(font
					(size 0.7 0.7)
					(thickness 0.15)
				)
				(justify left bottom)
			)
		)
		(fp_text user "Author: Antmicro"
			(at -0.939 3.399 90)
			(layer "F.Fab")
			(effects
				(font
					(size 0.7 0.7)
					(thickness 0.15)
				)
				(justify left bottom)
			)
		)
		(pad "1" smd roundrect
			(at -0.48 0 90)
			(size 0.59 0.64)
			(layers "F.Cu" "F.Mask" "F.Paste")
			(roundrect_rratio 0.25)
			(net 3 "GND")
			(pintype "passive")
		)
		(pad "2" smd roundrect
			(at 0.48 0 90)
			(size 0.59 0.64)
			(layers "F.Cu" "F.Mask" "F.Paste")
			(roundrect_rratio 0.25)
			(net 108 "Net-(U801-CLK_XTAL1)")
			(pintype "passive")
		)
	)
	(footprint "antmicro-footprints:TP_SMD_0.75mm"
		(layer "F.Cu")
		(at 98.775 124.375)
		(property "Reference" "TP901"
			(at -3.525 -0.225 0)
			(layer "F.SilkS")
			(effects
				(font
					(size 0.7 0.7)
					(thickness 0.15)
				)
				(justify left bottom)
			)
		)
		(property "Value" "TP_0.75mm_SMD"
			(at 0 1.2 0)
			(layer "F.Fab")
			(effects
				(font
					(size 0.7 0.7)
					(thickness 0.15)
				)
				(justify left bottom)
			)
		)
		(property "MPN" ""
			(at 0 0 0)
			(unlocked yes)
			(layer "F.Fab")
			(hide yes)
			(effects
				(font
					(size 1 1)
					(thickness 0.15)
				)
			)
		)
		(property "Manufacturer" ""
			(at 0 0 0)
			(unlocked yes)
			(layer "F.Fab")
			(hide yes)
			(effects
				(font
					(size 1 1)
					(thickness 0.15)
				)
			)
		)
		(property "Author" "Antmicro"
			(at 0 0 0)
			(unlocked yes)
			(layer "F.Fab")
			(hide yes)
			(effects
				(font
					(size 1 1)
					(thickness 0.15)
				)
			)
		)
		(property "License" "Apache-2.0"
			(at 0 0 0)
			(unlocked yes)
			(layer "F.Fab")
			(hide yes)
			(effects
				(font
					(size 1 1)
					(thickness 0.15)
				)
			)
		)
		(sheetname "/USB/")
		(sheetfile "usb.kicad_sch")
		(attr exclude_from_pos_files exclude_from_bom)
		(fp_circle
			(center 0 0)
			(end 0.475 0)
			(stroke
				(width 0.05)
				(type default)
			)
			(fill no)
			(layer "F.CrtYd")
		)
		(fp_text user "Author: Antmicro"
			(at -0.4 3.901 0)
			(layer "F.Fab")
			(effects
				(font
					(size 0.7 0.7)
					(thickness 0.15)
				)
				(justify left bottom)
			)
		)
		(fp_text user "${REFERENCE}"
			(at -0.4 2.7 0)
			(layer "F.Fab")
			(effects
				(font
					(size 0.7 0.7)
					(thickness 0.15)
				)
				(justify left bottom)
			)
		)
		(fp_text user "License: Apache-2.0"
			(at -0.4 5.101 0)
			(layer "F.Fab")
			(effects
				(font
					(size 0.7 0.7)
					(thickness 0.15)
				)
				(justify left bottom)
			)
		)
		(pad "1" smd circle
			(at 0 0)
			(size 0.75 0.75)
			(layers "F.Cu" "F.Mask")
			(net 433 "Net-(U906-DIR)")
			(pinfunction "1")
			(pintype "passive")
		)
	)
	(footprint "antmicro-footprints:R_0402_1005Metric"
		(layer "F.Cu")
		(at 100.267962 149.6165 90)
		(descr "Resistor SMD 0402")
		(tags "resistor SMD 0402")
		(property "Reference" "R204"
			(at -3.5585 0.282038 90)
			(layer "F.SilkS")
			(effects
				(font
					(size 0.7 0.7)
					(thickness 0.15)
				)
				(justify left bottom)
			)
		)
		(property "Value" "R_100k_0402"
			(at -1.011843 1.772047 90)
			(layer "F.Fab")
			(effects
				(font
					(size 0.7 0.7)
					(thickness 0.15)
				)
				(justify left bottom)
			)
		)
		(property "Datasheet" "https://www.bourns.com/docs/product-datasheets/cr.pdf"
			(at 0 0 90)
			(layer "F.Fab")
			(hide yes)
			(effects
				(font
					(size 1.27 1.27)
					(thickness 0.15)
				)
			)
		)
		(property "MPN" "CR0402-FX-1003GLF"
			(at 0 0 90)
			(unlocked yes)
			(layer "F.Fab")
			(hide yes)
			(effects
				(font
					(size 1 1)
					(thickness 0.15)
				)
			)
		)
		(property "Manufacturer" "Bourns"
			(at 0 0 90)
			(unlocked yes)
			(layer "F.Fab")
			(hide yes)
			(effects
				(font
					(size 1 1)
					(thickness 0.15)
				)
			)
		)
		(property "License" "Apache-2.0"
			(at 0 0 90)
			(unlocked yes)
			(layer "F.Fab")
			(hide yes)
			(effects
				(font
					(size 1 1)
					(thickness 0.15)
				)
			)
		)
		(property "Author" "Antmicro"
			(at 0 0 90)
			(unlocked yes)
			(layer "F.Fab")
			(hide yes)
			(effects
				(font
					(size 1 1)
					(thickness 0.15)
				)
			)
		)
		(property "Val" "100k"
			(at 0 0 90)
			(unlocked yes)
			(layer "F.Fab")
			(hide yes)
			(effects
				(font
					(size 1 1)
					(thickness 0.15)
				)
			)
		)
		(property "Tolerance" "1%"
			(at 0 0 90)
			(unlocked yes)
			(layer "F.Fab")
			(hide yes)
			(effects
				(font
					(size 1 1)
					(thickness 0.15)
				)
			)
		)
		(sheetname "/Compute module/")
		(sheetfile "compute-module.kicad_sch")
		(attr smd)
		(fp_rect
			(start -0.925 -0.47)
			(end 0.925 0.47)
			(stroke
				(width 0.05)
				(type default)
			)
			(fill no)
			(layer "F.CrtYd")
		)
		(fp_rect
			(start -0.5 -0.25)
			(end 0.5 0.25)
			(stroke
				(width 0.15)
				(type solid)
			)
			(fill no)
			(layer "F.Fab")
		)
		(fp_text user "License: Apache-2.0"
			(at -0.95 5.169 90)
			(layer "F.Fab")
			(effects
				(font
					(size 0.7 0.7)
					(thickness 0.15)
				)
				(justify left bottom)
			)
		)
		(fp_text user "Author: Antmicro"
			(at -0.95 4.169 90)
			(layer "F.Fab")
			(effects
				(font
					(size 0.7 0.7)
					(thickness 0.15)
				)
				(justify left bottom)
			)
		)
		(fp_text user "${REFERENCE}"
			(at -0.95 3.168 90)
			(layer "F.Fab")
			(effects
				(font
					(size 0.7 0.7)
					(thickness 0.15)
				)
				(justify left bottom)
			)
		)
		(pad "1" smd roundrect
			(at -0.48 0 90)
			(size 0.59 0.64)
			(layers "F.Cu" "F.Mask" "F.Paste")
			(roundrect_rratio 0.25)
			(net 3 "GND")
			(pintype "passive")
		)
		(pad "2" smd roundrect
			(at 0.48 0 90)
			(size 0.59 0.64)
			(layers "F.Cu" "F.Mask" "F.Paste")
			(roundrect_rratio 0.25)
			(net 231 "/Compute module/PolarfireID")
			(pintype "passive")
		)
	)
	(footprint "antmicro-footprints:SOT-523"
		(layer "F.Cu")
		(at 141.727962 128.0815 180)
		(property "Reference" "Q207"
			(at 1.35 1.255 90)
			(layer "F.SilkS")
			(effects
				(font
					(size 0.7 0.7)
					(thickness 0.15)
				)
				(justify right bottom)
			)
		)
		(property "Value" "PJE138K"
			(at 0.1 1.824 0)
			(layer "F.Fab")
			(effects
				(font
					(size 0.7 0.7)
					(thickness 0.15)
				)
				(justify right bottom)
			)
		)
		(property "Datasheet" "https://www.mouser.com/datasheet/2/1057/PJE138K-1876698.pdf"
			(at 0 0 180)
			(layer "F.Fab")
			(hide yes)
			(effects
				(font
					(size 1.27 1.27)
					(thickness 0.15)
				)
			)
		)
		(property "MPN" "PJE138K_R1_00001"
			(at 0 0 180)
			(unlocked yes)
			(layer "F.Fab")
			(hide yes)
			(effects
				(font
					(size 1 1)
					(thickness 0.15)
				)
			)
		)
		(property "Manufacturer" "PANJIT"
			(at 0 0 180)
			(unlocked yes)
			(layer "F.Fab")
			(hide yes)
			(effects
				(font
					(size 1 1)
					(thickness 0.15)
				)
			)
		)
		(property "Author" "Antmicro"
			(at 0 0 180)
			(unlocked yes)
			(layer "F.Fab")
			(hide yes)
			(effects
				(font
					(size 1 1)
					(thickness 0.15)
				)
			)
		)
		(property "License" "Apache-2.0"
			(at 0 0 180)
			(unlocked yes)
			(layer "F.Fab")
			(hide yes)
			(effects
				(font
					(size 1 1)
					(thickness 0.15)
				)
			)
		)
		(sheetname "/Compute module/")
		(sheetfile "compute-module.kicad_sch")
		(attr smd)
		(fp_line
			(start -0.277 -0.551)
			(end -0.277 -0.75)
			(stroke
				(width 0.15)
				(type solid)
			)
			(layer "F.SilkS")
		)
		(fp_line
			(start -0.725 -0.551)
			(end -0.277 -0.551)
			(stroke
				(width 0.15)
				(type solid)
			)
			(layer "F.SilkS")
		)
		(fp_line
			(start -0.927 -0.051)
			(end -0.927 -0.351)
			(stroke
				(width 0.15)
				(type solid)
			)
			(layer "F.SilkS")
		)
		(fp_line
			(start -0.927 -0.351)
			(end -0.725 -0.551)
			(stroke
				(width 0.15)
				(type solid)
			)
			(layer "F.SilkS")
		)
		(fp_circle
			(center -0.9652 0.9652)
			(end -0.9152 0.9652)
			(stroke
				(width 0.15)
				(type solid)
			)
			(fill yes)
			(layer "F.SilkS")
		)
		(fp_line
			(start 1.1 -1.16)
			(end 1.1 1.15)
			(stroke
				(width 0.05)
				(type solid)
			)
			(layer "F.CrtYd")
		)
		(fp_line
			(start -1.12 1.15)
			(end 1.1 1.15)
			(stroke
				(width 0.05)
				(type solid)
			)
			(layer "F.CrtYd")
		)
		(fp_line
			(start -1.12 -1.16)
			(end 1.1 -1.16)
			(stroke
				(width 0.05)
				(type solid)
			)
			(layer "F.CrtYd")
		)
		(fp_line
			(start -1.12 -1.16)
			(end -1.12 1.15)
			(stroke
				(width 0.05)
				(type solid)
			)
			(layer "F.CrtYd")
		)
		(fp_line
			(start 0.8 0.424)
			(end -0.802 0.424)
			(stroke
				(width 0.15)
				(type solid)
			)
			(layer "F.Fab")
		)
		(fp_line
			(start 0.8 -0.425)
			(end 0.8 0.424)
			(stroke
				(width 0.15)
				(type solid)
			)
			(layer "F.Fab")
		)
		(fp_line
			(start 0.8 -0.425)
			(end -0.652 -0.425)
			(stroke
				(width 0.15)
				(type solid)
			)
			(layer "F.Fab")
		)
		(fp_line
			(start -0.652 -0.425)
			(end -0.802 -0.276)
			(stroke
				(width 0.15)
				(type solid)
			)
			(layer "F.Fab")
		)
		(fp_line
			(start -0.802 -0.276)
			(end -0.802 0.424)
			(stroke
				(width 0.15)
				(type solid)
			)
			(layer "F.Fab")
		)
		(fp_circle
			(center -0.9652 0.9652)
			(end -0.9144 0.9652)
			(stroke
				(width 0.15)
				(type solid)
			)
			(fill no)
			(layer "F.Fab")
		)
		(fp_text user "License: Apache-2.0"
			(at -1.12 5.024 180)
			(layer "F.Fab")
			(effects
				(font
					(size 0.7 0.7)
					(thickness 0.15)
				)
				(justify left bottom)
			)
		)
		(fp_text user "${REFERENCE}"
			(at -1.12 3.824 180)
			(layer "F.Fab")
			(effects
				(font
					(size 0.7 0.7)
					(thickness 0.15)
				)
				(justify left bottom)
			)
		)
		(fp_text user "Author: Antmicro"
			(at -1.12 6.224 180)
			(layer "F.Fab")
			(effects
				(font
					(size 0.7 0.7)
					(thickness 0.15)
				)
				(justify left bottom)
			)
		)
		(pad "1" smd rect
			(at -0.5 0.65 180)
			(size 0.4 0.51)
			(layers "F.Cu" "F.Mask" "F.Paste")
			(net 329 "Net-(Q207-G)")
			(pinfunction "G")
			(pintype "input")
		)
		(pad "2" smd rect
			(at 0.498 0.65 180)
			(size 0.4 0.51)
			(layers "F.Cu" "F.Mask" "F.Paste")
			(net 3 "GND")
			(pinfunction "S")
			(pintype "passive")
		)
		(pad "3" smd rect
			(at 0 -0.652 180)
			(size 0.4 0.51)
			(layers "F.Cu" "F.Mask" "F.Paste")
			(net 250 "/Compute module/~{RPi_BOOT}")
			(pinfunction "D")
			(pintype "passive")
		)
	)
	(footprint "antmicro-footprints:C_0402_1005Metric"
		(layer "F.Cu")
		(at 129.267962 118.6665)
		(descr "Capacitor SMD 0402")
		(tags "capacitor SMD 0402")
		(property "Reference" "C202"
			(at -3.78 -0.1 0)
			(layer "F.SilkS")
			(effects
				(font
					(size 0.7 0.7)
					(thickness 0.15)
				)
				(justify left bottom)
			)
		)
		(property "Value" "C_100n_0402"
			(at -1.022927 2.155213 0)
			(layer "F.Fab")
			(effects
				(font
					(size 0.7 0.7)
					(thickness 0.15)
				)
				(justify left bottom)
			)
		)
		(property "Datasheet" "https://www.murata.com/products/productdetail?partno=GRM155R61H104KE14%23"
			(at 0 0 0)
			(layer "F.Fab")
			(hide yes)
			(effects
				(font
					(size 1.27 1.27)
					(thickness 0.15)
				)
			)
		)
		(property "Manufacturer" "Murata"
			(at 0 0 0)
			(unlocked yes)
			(layer "F.Fab")
			(hide yes)
			(effects
				(font
					(size 1 1)
					(thickness 0.15)
				)
			)
		)
		(property "MPN" "GRM155R61H104KE14D"
			(at 0 0 0)
			(unlocked yes)
			(layer "F.Fab")
			(hide yes)
			(effects
				(font
					(size 1 1)
					(thickness 0.15)
				)
			)
		)
		(property "Val" "100n"
			(at 0 0 0)
			(unlocked yes)
			(layer "F.Fab")
			(hide yes)
			(effects
				(font
					(size 1 1)
					(thickness 0.15)
				)
			)
		)
		(property "License" "Apache-2.0"
			(at 0 0 0)
			(unlocked yes)
			(layer "F.Fab")
			(hide yes)
			(effects
				(font
					(size 1 1)
					(thickness 0.15)
				)
			)
		)
		(property "Author" "Antmicro"
			(at 0 0 0)
			(unlocked yes)
			(layer "F.Fab")
			(hide yes)
			(effects
				(font
					(size 1 1)
					(thickness 0.15)
				)
			)
		)
		(property "Voltage" "50V"
			(at 0 0 0)
			(unlocked yes)
			(layer "F.Fab")
			(hide yes)
			(effects
				(font
					(size 1 1)
					(thickness 0.15)
				)
			)
		)
		(property "Dielectric" "X5R"
			(at 0 0 0)
			(unlocked yes)
			(layer "F.Fab")
			(hide yes)
			(effects
				(font
					(size 1 1)
					(thickness 0.15)
				)
			)
		)
		(sheetname "/Compute module/")
		(sheetfile "compute-module.kicad_sch")
		(attr smd)
		(fp_rect
			(start -0.925 -0.47)
			(end 0.925 0.47)
			(stroke
				(width 0.05)
				(type default)
			)
			(fill no)
			(layer "F.CrtYd")
		)
		(fp_line
			(start -0.494 -0.25)
			(end 0.504 -0.25)
			(stroke
				(width 0.15)
				(type solid)
			)
			(layer "F.Fab")
		)
		(fp_line
			(start -0.494 0.248)
			(end -0.494 -0.25)
			(stroke
				(width 0.15)
				(type solid)
			)
			(layer "F.Fab")
		)
		(fp_line
			(start 0.504 -0.25)
			(end 0.504 0.248)
			(stroke
				(width 0.15)
				(type solid)
			)
			(layer "F.Fab")
		)
		(fp_line
			(start 0.504 0.248)
			(end -0.494 0.248)
			(stroke
				(width 0.15)
				(type solid)
			)
			(layer "F.Fab")
		)
		(fp_text user "Author: Antmicro"
			(at -0.939 3.399 0)
			(layer "F.Fab")
			(effects
				(font
					(size 0.7 0.7)
					(thickness 0.15)
				)
				(justify left bottom)
			)
		)
		(fp_text user "${REFERENCE}"
			(at -0.939 4.599 0)
			(layer "F.Fab")
			(effects
				(font
					(size 0.7 0.7)
					(thickness 0.15)
				)
				(justify left bottom)
			)
		)
		(fp_text user "License: Apache-2.0"
			(at -0.939 5.799 0)
			(layer "F.Fab")
			(effects
				(font
					(size 0.7 0.7)
					(thickness 0.15)
				)
				(justify left bottom)
			)
		)
		(pad "1" smd roundrect
			(at -0.48 0)
			(size 0.59 0.64)
			(layers "F.Cu" "F.Mask" "F.Paste")
			(roundrect_rratio 0.25)
			(net 3 "GND")
			(pintype "passive")
		)
		(pad "2" smd roundrect
			(at 0.48 0)
			(size 0.59 0.64)
			(layers "F.Cu" "F.Mask" "F.Paste")
			(roundrect_rratio 0.25)
			(net 4 "Net-(D204-A)")
			(pintype "passive")
		)
	)
)
